(kicad_pcb
	(version 20260206)
	(generator "pcbnew")
	(generator_version "10.0")
	(general
		(thickness 1.21888)
		(legacy_teardrops no)
	)
	(paper "A4")
	(title_block
		(title "timecard-proto-v0 — Timingcard_PCB.PcbDoc")
		(comment 1 "Time Appliance Project (Time Card) / footprints 44-56 of 167")
	)
	(layers
		(0 "F.Cu" signal "TOP")
		(4 "In1.Cu" signal "SGND")
		(6 "In2.Cu" signal "IN1")
		(8 "In3.Cu" signal "IN2")
		(10 "In4.Cu" signal "SGND1")
		(2 "B.Cu" signal "BOTTOM")
		(9 "F.Adhes" user "F.Adhesive")
		(11 "B.Adhes" user "B.Adhesive")
		(13 "F.Paste" user "Top Paste")
		(15 "B.Paste" user "Bottom Paste")
		(5 "F.SilkS" user "Top Overlay")
		(7 "B.SilkS" user "Bottom Overlay")
		(1 "F.Mask" user "Top Solder")
		(3 "B.Mask" user "Bottom Solder")
		(17 "Dwgs.User" user "User.Drawings")
		(19 "Cmts.User" user "User.Comments")
		(21 "Eco1.User" user "User.Eco1")
		(23 "Eco2.User" user "User.Eco2")
		(25 "Edge.Cuts" user)
		(27 "Margin" user)
		(31 "F.CrtYd" user "Top Courtyard")
		(29 "B.CrtYd" user "Bottom Courtyard")
		(35 "F.Fab" user "Top Component Center")
		(33 "B.Fab" user "Bottom Component Center")
	)
	(footprint "Connectors:39-30-1060"
		(layer "F.Cu")
		(at 225.353595 69.4046 180)
		(property "Reference" "J2"
			(at -9.185 -3.142345 0)
			(unlocked yes)
			(layer "F.SilkS")
			(effects
				(font
					(size 0.762 0.762)
					(thickness 0.2286)
				)
				(justify left bottom)
			)
		)
		(property "Value" "39-30-1060"
			(at 2.8141 -11.19579 0)
			(unlocked yes)
			(layer "F.SilkS")
			(hide yes)
			(effects
				(font
					(size 1.524 1.524)
					(thickness 0.254)
				)
				(justify left bottom)
			)
		)
		(sheetname "POWER")
		(sheetfile "POWER.kicad_sch")
		(duplicate_pad_numbers_are_jumpers no)
		(fp_line
			(start 3.175 -1.524)
			(end 3.175 19.49249)
			(stroke
				(width 0.2032)
				(type solid)
			)
			(layer "F.SilkS")
		)
		(fp_line
			(start 3.175 -1.524)
			(end -11.02502 -1.524)
			(stroke
				(width 0.2032)
				(type solid)
			)
			(layer "F.SilkS")
		)
		(fp_line
			(start -11.02502 -0.44249)
			(end -11.02502 19.49249)
			(stroke
				(width 0.2032)
				(type solid)
			)
			(layer "F.SilkS")
		)
		(fp_line
			(start -11.02502 -1.51445)
			(end -11.02502 -0.44249)
			(stroke
				(width 0.203)
				(type solid)
			)
			(layer "F.SilkS")
		)
		(pad "" np_thru_hole circle
			(at -8.4 12.8 180)
			(size 1.27 1.27)
			(drill 3)
			(layers "*.Cu" "*.Mask")
			(thermal_bridge_angle 90)
		)
		(pad "" np_thru_hole circle
			(at 0 12.8 180)
			(size 1.27 1.27)
			(drill 3)
			(layers "*.Cu" "*.Mask")
			(thermal_bridge_angle 90)
			(padstack
				(mode front_inner_back)
				(layer "Inner"
					(shape circle)
					(size 1.27 1.27)
				)
				(layer "B.Cu"
					(shape circle)
					(size 1.27 1.27)
				)
			)
		)
		(pad "1" thru_hole circle
			(at 0 5.5 270)
			(size 2.5 2.5)
			(drill 1.8)
			(layers "*.Cu" "*.Mask")
			(remove_unused_layers no)
			(net "NetD2_2")
			(thermal_bridge_angle 90)
		)
		(pad "2" thru_hole circle
			(at -4.2 5.5 270)
			(size 2.5 2.5)
			(drill 1.8)
			(layers "*.Cu" "*.Mask")
			(remove_unused_layers no)
			(net "NetD2_2")
			(thermal_bridge_angle 90)
		)
		(pad "3" thru_hole circle
			(at -8.4 5.5 270)
			(size 2.5 2.5)
			(drill 1.8)
			(layers "*.Cu" "*.Mask")
			(remove_unused_layers no)
			(net "NetD2_2")
			(thermal_bridge_angle 90)
		)
		(pad "4" thru_hole circle
			(at 0 0 270)
			(size 2.5 2.5)
			(drill 1.8)
			(layers "*.Cu" "*.Mask")
			(remove_unused_layers no)
			(net "GND")
			(thermal_bridge_angle 90)
		)
		(pad "5" thru_hole circle
			(at -4.2 0 270)
			(size 2.5 2.5)
			(drill 1.8)
			(layers "*.Cu" "*.Mask")
			(remove_unused_layers no)
			(net "GND")
			(thermal_bridge_angle 90)
		)
		(pad "6" thru_hole circle
			(at -8.4 0 270)
			(size 2.5 2.5)
			(drill 1.8)
			(layers "*.Cu" "*.Mask")
			(remove_unused_layers no)
			(net "GND")
			(thermal_bridge_angle 90)
		)
	)
	(footprint "Vault:CAPC1608X87X45ML20T05"
		(layer "F.Cu")
		(at 152.288595 144.1786)
		(property "Reference" "C63"
			(at -4.8 0.193345 0)
			(unlocked yes)
			(layer "F.SilkS")
			(effects
				(font
					(size 0.762 0.762)
					(thickness 0.2286)
				)
				(justify left bottom)
			)
		)
		(property "Value" "0.1uF"
			(at -0.2921 3.47599 0)
			(unlocked yes)
			(layer "F.SilkS")
			(hide yes)
			(effects
				(font
					(size 1.524 1.524)
					(thickness 0.254)
				)
				(justify left bottom)
			)
		)
		(sheetname "MAC")
		(sheetfile "MAC.kicad_sch")
		(duplicate_pad_numbers_are_jumpers no)
		(pad "1" smd rect
			(at -0.7 0 90)
			(size 1.1 1.05)
			(layers "F.Cu" "F.Mask" "F.Paste")
			(net "GND")
		)
		(pad "2" smd rect
			(at 0.7 0 90)
			(size 1.1 1.05)
			(layers "F.Cu" "F.Mask" "F.Paste")
			(net "+5.0V")
		)
	)
	(footprint "Passives:DIOM1608X06N"
		(layer "F.Cu")
		(at 149.670595 61.9996 -90)
		(property "Reference" "D9"
			(at -1.921 -0.411345 90)
			(unlocked yes)
			(layer "F.SilkS")
			(effects
				(font
					(size 0.762 0.762)
					(thickness 0.2286)
				)
				(justify left bottom)
			)
		)
		(property "Value" "RED"
			(at 3.22199 1.4097 0)
			(unlocked yes)
			(layer "F.SilkS")
			(hide yes)
			(effects
				(font
					(size 1.524 1.524)
					(thickness 0.254)
				)
				(justify left bottom)
			)
		)
		(sheetname "UART")
		(sheetfile "UART.kicad_sch")
		(duplicate_pad_numbers_are_jumpers no)
		(fp_circle
			(center -1.275 -0.725)
			(end -1.325 -0.725)
			(stroke
				(width 0.1)
				(type solid)
			)
			(fill no)
			(layer "F.SilkS")
		)
		(pad "1" smd rect
			(at -0.725 0)
			(size 0.85 1)
			(layers "F.Cu" "F.Mask" "F.Paste")
			(net "NetD9_1")
		)
		(pad "2" smd rect
			(at 0.725 0)
			(size 0.85 1)
			(layers "F.Cu" "F.Mask" "F.Paste")
			(net "+3.3V")
		)
	)
	(footprint "Miscellaneous:OMRON-B3U-1000P"
		(layer "F.Cu")
		(at 172.784595 53.7446)
		(property "Reference" "S5"
			(at -2.3622 -2.218055 0)
			(unlocked yes)
			(layer "F.SilkS")
			(effects
				(font
					(size 0.762 0.762)
					(thickness 0.2286)
				)
				(justify left bottom)
			)
		)
		(property "Value" "B3U-1000P"
			(at -2.3241 4.03479 0)
			(unlocked yes)
			(layer "F.SilkS")
			(hide yes)
			(effects
				(font
					(size 1.524 1.524)
					(thickness 0.254)
				)
				(justify left bottom)
			)
		)
		(sheetname "USER_IO")
		(sheetfile "USER_IO.kicad_sch")
		(duplicate_pad_numbers_are_jumpers no)
		(fp_line
			(start -2.286 -1.397)
			(end 2.286 -1.397)
			(stroke
				(width 0.2032)
				(type solid)
			)
			(layer "F.SilkS")
		)
		(fp_line
			(start -2.286 -1.143)
			(end -2.286 -1.397)
			(stroke
				(width 0.2032)
				(type solid)
			)
			(layer "F.SilkS")
		)
		(fp_line
			(start -2.286 1.397)
			(end -2.286 1.143)
			(stroke
				(width 0.2032)
				(type solid)
			)
			(layer "F.SilkS")
		)
		(fp_line
			(start -2.286 1.397)
			(end 2.286 1.397)
			(stroke
				(width 0.2032)
				(type solid)
			)
			(layer "F.SilkS")
		)
		(fp_line
			(start 2.286 -1.143)
			(end 2.286 -1.397)
			(stroke
				(width 0.2032)
				(type solid)
			)
			(layer "F.SilkS")
		)
		(fp_line
			(start 2.286 1.397)
			(end 2.286 1.143)
			(stroke
				(width 0.2032)
				(type solid)
			)
			(layer "F.SilkS")
		)
		(pad "1" smd rect
			(at -1.7 0)
			(size 0.8 1.7)
			(layers "F.Cu" "F.Mask" "F.Paste")
			(net "GND")
		)
		(pad "2" smd rect
			(at 1.7 0)
			(size 0.8 1.7)
			(layers "F.Cu" "F.Mask" "F.Paste")
			(net "NetR33_1")
		)
	)
	(footprint "Vault:MCSM-090-02984-00X"
		(layer "F.Cu")
		(at 181.113595 118.4786 90)
		(property "Reference" "U10AL"
			(at 21.552349 -15.555855 0)
			(unlocked yes)
			(layer "F.SilkS")
			(effects
				(font
					(size 0.762 0.762)
					(thickness 0.254)
				)
			)
		)
		(property "Value" "SA.45s"
			(at -22.749002 -13.069655 0)
			(unlocked yes)
			(layer "F.SilkS")
			(hide yes)
			(effects
				(font
					(size 1.524 1.524)
					(thickness 0.254)
				)
			)
		)
		(sheetname "MAC")
		(sheetfile "MAC.kicad_sch")
		(duplicate_pad_numbers_are_jumpers no)
		(fp_line
			(start 20.32 -17.653)
			(end 20.32 17.653)
			(stroke
				(width 0.2)
				(type solid)
			)
			(layer "F.SilkS")
		)
		(fp_line
			(start -20.32 -17.653)
			(end 20.32 -17.653)
			(stroke
				(width 0.2)
				(type solid)
			)
			(layer "F.SilkS")
		)
		(fp_line
			(start -20.32 -17.653)
			(end -20.32 17.653)
			(stroke
				(width 0.2)
				(type solid)
			)
			(layer "F.SilkS")
		)
		(fp_line
			(start -20.32 17.653)
			(end 20.32 17.653)
			(stroke
				(width 0.2)
				(type solid)
			)
			(layer "F.SilkS")
		)
		(fp_circle
			(center -20.92 -12.7)
			(end -20.795 -12.7)
			(stroke
				(width 0.25)
				(type solid)
			)
			(fill no)
			(layer "F.SilkS")
		)
		(pad "1" thru_hole rect
			(at -16.51 -12.7 90)
			(size 1.55 1.55)
			(drill 1.05)
			(layers "*.Cu" "*.Mask")
			(remove_unused_layers no)
		)
		(pad "4" thru_hole circle
			(at -16.51 2.54 90)
			(size 1.55 1.55)
			(drill 1.05)
			(layers "*.Cu" "*.Mask")
			(remove_unused_layers no)
			(net "MAC_BITE")
			(thermal_bridge_angle 90)
		)
		(pad "5" thru_hole circle
			(at -16.51 7.62 90)
			(size 1.55 1.55)
			(drill 1.05)
			(layers "*.Cu" "*.Mask")
			(remove_unused_layers no)
			(net "MAC_TX")
			(thermal_bridge_angle 90)
		)
		(pad "6" thru_hole circle
			(at -16.51 12.7 90)
			(size 1.55 1.55)
			(drill 1.05)
			(layers "*.Cu" "*.Mask")
			(remove_unused_layers no)
			(net "MAC_RX")
			(thermal_bridge_angle 90)
		)
		(pad "7" thru_hole circle
			(at 16.51 12.7 90)
			(size 1.55 1.55)
			(drill 1.05)
			(layers "*.Cu" "*.Mask")
			(remove_unused_layers no)
			(net "+3.3V_CLEAN")
			(thermal_bridge_angle 90)
		)
		(pad "8" thru_hole circle
			(at 16.51 7.62 90)
			(size 1.55 1.55)
			(drill 1.05)
			(layers "*.Cu" "*.Mask")
			(remove_unused_layers no)
			(net "GND")
			(thermal_bridge_angle 90)
		)
		(pad "9" thru_hole circle
			(at 16.51 2.54 90)
			(size 1.55 1.55)
			(drill 1.05)
			(layers "*.Cu" "*.Mask")
			(remove_unused_layers no)
			(net "MAC_PPS_IN0+")
			(thermal_bridge_angle 90)
		)
		(pad "10" thru_hole circle
			(at 16.51 -2.54 90)
			(size 1.55 1.55)
			(drill 1.05)
			(layers "*.Cu" "*.Mask")
			(remove_unused_layers no)
			(net "MAC_PPS_OUT+")
			(thermal_bridge_angle 90)
		)
		(pad "12" thru_hole circle
			(at 16.51 -12.7 90)
			(size 1.55 1.55)
			(drill 1.05)
			(layers "*.Cu" "*.Mask")
			(remove_unused_layers no)
			(net "MAC_10Mout")
			(thermal_bridge_angle 90)
		)
	)
	(footprint "Vault:RESC1608X55X30LL15T20"
		(layer "F.Cu")
		(at 170.688595 60.7786)
		(property "Reference" "R37"
			(at -2.1714 0.026921 0)
			(unlocked yes)
			(layer "F.SilkS")
			(effects
				(font
					(size 0.762 0.762)
					(thickness 0.2286)
				)
			)
		)
		(property "Value" "10K"
			(at -2.657602 1.790085 270)
			(unlocked yes)
			(layer "F.SilkS")
			(hide yes)
			(effects
				(font
					(size 1.524 1.524)
					(thickness 0.254)
				)
			)
		)
		(sheetname "GPS_IMU_SENSORS")
		(sheetfile "GPS_IMU_SENSORS.kicad_sch")
		(duplicate_pad_numbers_are_jumpers no)
		(pad "1" smd rect
			(at -0.575 0 90)
			(size 0.85 0.75)
			(layers "F.Cu" "F.Mask" "F.Paste")
			(net "EXT_EEPROM_WP")
		)
		(pad "2" smd rect
			(at 0.575 0 90)
			(size 0.85 0.75)
			(layers "F.Cu" "F.Mask" "F.Paste")
			(net "+3.3V")
		)
	)
	(footprint "Capacitors:CAPC1608X10N"
		(layer "F.Cu")
		(at 152.185195 76.8078 -90)
		(property "Reference" "C67"
			(at -2.243455 0.5842 0)
			(unlocked yes)
			(layer "F.SilkS")
			(effects
				(font
					(size 0.762 0.762)
					(thickness 0.2286)
				)
				(justify left bottom)
			)
		)
		(property "Value" "CAP_0603_0.01UF_50V"
			(at 4.08559 0.5461 0)
			(unlocked yes)
			(layer "F.SilkS")
			(hide yes)
			(effects
				(font
					(size 1.524 1.524)
					(thickness 0.254)
				)
				(justify left bottom)
			)
		)
		(sheetname "MAC")
		(sheetfile "MAC.kicad_sch")
		(duplicate_pad_numbers_are_jumpers no)
		(fp_line
			(start 0.635 0.7112)
			(end -0.635 0.7112)
			(stroke
				(width 0.1524)
				(type solid)
			)
			(layer "F.SilkS")
		)
		(fp_line
			(start 0.635 -0.7112)
			(end -0.635 -0.7112)
			(stroke
				(width 0.1524)
				(type solid)
			)
			(layer "F.SilkS")
		)
		(pad "1" smd rect
			(at -0.8 0)
			(size 0.95 1)
			(layers "F.Cu" "F.Mask" "F.Paste")
			(net "GND")
		)
		(pad "2" smd rect
			(at 0.8 0)
			(size 0.95 1)
			(layers "F.Cu" "F.Mask" "F.Paste")
			(net "+3.3V_CLEAN")
		)
	)
	(footprint "Capacitors:CAPC1608X10N"
		(layer "F.Cu")
		(at 101.562995 52.0428 180)
		(property "Reference" "C92"
			(at 4.82551 -0.563055 0)
			(unlocked yes)
			(layer "F.SilkS")
			(effects
				(font
					(size 0.762 0.762)
					(thickness 0.2286)
				)
				(justify left bottom)
			)
		)
		(property "Value" "GRT188R61E106ME13D"
			(at 0.5461 -4.08559 0)
			(unlocked yes)
			(layer "F.SilkS")
			(hide yes)
			(effects
				(font
					(size 1.524 1.524)
					(thickness 0.254)
				)
				(justify left bottom)
			)
		)
		(sheetname "GPS_IMU_SENSORS")
		(sheetfile "GPS_IMU_SENSORS.kicad_sch")
		(duplicate_pad_numbers_are_jumpers no)
		(fp_line
			(start 0.635 0.7112)
			(end -0.635 0.7112)
			(stroke
				(width 0.1524)
				(type solid)
			)
			(layer "F.SilkS")
		)
		(fp_line
			(start 0.635 -0.7112)
			(end -0.635 -0.7112)
			(stroke
				(width 0.1524)
				(type solid)
			)
			(layer "F.SilkS")
		)
		(pad "1" smd rect
			(at -0.8 0 270)
			(size 0.95 1)
			(layers "F.Cu" "F.Mask" "F.Paste")
			(net "GND")
		)
		(pad "2" smd rect
			(at 0.8 0 270)
			(size 0.95 1)
			(layers "F.Cu" "F.Mask" "F.Paste")
			(net "+5.0V")
		)
	)
	(footprint "Capacitors:CAPC2012X14N"
		(layer "F.Cu")
		(at 227.648595 106.4496 90)
		(property "Reference" "C6"
			(at 2.046 0.483345 90)
			(unlocked yes)
			(layer "F.SilkS")
			(effects
				(font
					(size 0.762 0.762)
					(thickness 0.2286)
				)
				(justify left bottom)
			)
		)
		(property "Value" "CAP_0805_10UF_25V"
			(at -3.39979 -5.0165 0)
			(unlocked yes)
			(layer "F.SilkS")
			(hide yes)
			(effects
				(font
					(size 1.524 1.524)
					(thickness 0.254)
				)
				(justify left bottom)
			)
		)
		(sheetname "POWER")
		(sheetfile "POWER.kicad_sch")
		(duplicate_pad_numbers_are_jumpers no)
		(fp_line
			(start -0.762 -0.9652)
			(end 0.762 -0.9652)
			(stroke
				(width 0.1524)
				(type solid)
			)
			(layer "F.SilkS")
		)
		(fp_line
			(start -0.762 0.9652)
			(end 0.762 0.9652)
			(stroke
				(width 0.1524)
				(type solid)
			)
			(layer "F.SilkS")
		)
		(pad "1" smd rect
			(at -0.9 0 180)
			(size 1.45 1.15)
			(layers "F.Cu" "F.Mask" "F.Paste")
			(net "+12V")
		)
		(pad "2" smd rect
			(at 0.9 0 180)
			(size 1.45 1.15)
			(layers "F.Cu" "F.Mask" "F.Paste")
			(net "GND")
		)
	)
	(footprint "Resistors:RESC1005X04N"
		(layer "F.Cu")
		(at 136.088595 145.5786 -90)
		(property "Reference" "R24"
			(at 1.35111 0.884735 90)
			(unlocked yes)
			(layer "F.SilkS")
			(effects
				(font
					(size 0.762 0.762)
					(thickness 0.2286)
				)
				(justify left bottom)
			)
		)
		(property "Value" "ERJ-2GE0R00X"
			(at 3.42519 0.2413 0)
			(unlocked yes)
			(layer "F.SilkS")
			(hide yes)
			(effects
				(font
					(size 1.524 1.524)
					(thickness 0.254)
				)
				(justify left bottom)
			)
		)
		(sheetname "PCIe_JTAG")
		(sheetfile "PCIe_JTAG.kicad_sch")
		(duplicate_pad_numbers_are_jumpers no)
		(pad "1" smd rect
			(at -0.425 0)
			(size 0.6 0.65)
			(layers "F.Cu" "F.Mask" "F.Paste")
			(net "PRSNT")
		)
		(pad "2" smd rect
			(at 0.425 0)
			(size 0.6 0.65)
			(layers "F.Cu" "F.Mask" "F.Paste")
			(net "NetP2_B31")
		)
	)
	(footprint "Vault:CAPC1608X87X45ML20T05"
		(layer "F.Cu")
		(at 225.788595 83.5786 90)
		(property "Reference" "C57"
			(at -2.893345 -0.9 0)
			(unlocked yes)
			(layer "F.SilkS")
			(effects
				(font
					(size 0.762 0.762)
					(thickness 0.2286)
				)
				(justify left bottom)
			)
		)
		(property "Value" "0.1uF"
			(at 4.90601 11.6459 0)
			(unlocked yes)
			(layer "F.SilkS")
			(hide yes)
			(effects
				(font
					(size 1.524 1.524)
					(thickness 0.254)
				)
				(justify left bottom)
			)
		)
		(sheetname "GPS_IMU_SENSORS")
		(sheetfile "GPS_IMU_SENSORS.kicad_sch")
		(duplicate_pad_numbers_are_jumpers no)
		(pad "1" smd rect
			(at -0.7 0 180)
			(size 1.1 1.05)
			(layers "F.Cu" "F.Mask" "F.Paste")
			(net "GND")
		)
		(pad "2" smd rect
			(at 0.7 0 180)
			(size 1.1 1.05)
			(layers "F.Cu" "F.Mask" "F.Paste")
			(net "+3.3V")
		)
	)
	(footprint "Passives:DIOM1608X06N"
		(layer "F.Cu")
		(at 149.670595 65.1746 90)
		(property "Reference" "D10"
			(at -3.604 0.411345 90)
			(unlocked yes)
			(layer "F.SilkS")
			(effects
				(font
					(size 0.762 0.762)
					(thickness 0.2286)
				)
				(justify left bottom)
			)
		)
		(property "Value" "RED"
			(at -4.13639 -0.5715 0)
			(unlocked yes)
			(layer "F.SilkS")
			(hide yes)
			(effects
				(font
					(size 1.524 1.524)
					(thickness 0.254)
				)
				(justify left bottom)
			)
		)
		(sheetname "UART")
		(sheetfile "UART.kicad_sch")
		(duplicate_pad_numbers_are_jumpers no)
		(fp_circle
			(center -1.275 -0.725)
			(end -1.225 -0.725)
			(stroke
				(width 0.1)
				(type solid)
			)
			(fill no)
			(layer "F.SilkS")
		)
		(pad "1" smd rect
			(at -0.725 0 180)
			(size 0.85 1)
			(layers "F.Cu" "F.Mask" "F.Paste")
			(net "NetD10_1")
		)
		(pad "2" smd rect
			(at 0.725 0 180)
			(size 0.85 1)
			(layers "F.Cu" "F.Mask" "F.Paste")
			(net "+3.3V")
		)
	)
	(footprint "Passives:SOT65P210X110-3N"
		(layer "F.Cu")
		(at 146.622595 66.4446 -90)
		(property "Reference" "D8"
			(at -2.32441 -0.690065 90)
			(unlocked yes)
			(layer "F.SilkS")
			(effects
				(font
					(size 0.762 0.762)
					(thickness 0.2286)
				)
				(justify left bottom)
			)
		)
		(property "Value" "BAT54SW"
			(at 3.88239 1.5875 0)
			(unlocked yes)
			(layer "F.SilkS")
			(hide yes)
			(effects
				(font
					(size 1.524 1.524)
					(thickness 0.254)
				)
				(justify left bottom)
			)
		)
		(sheetname "PCIe_JTAG")
		(sheetfile "PCIe_JTAG.kicad_sch")
		(duplicate_pad_numbers_are_jumpers no)
		(fp_line
			(start 0.675 1.1)
			(end -0.325 1.1)
			(stroke
				(width 0.2)
				(type solid)
			)
			(layer "F.SilkS")
		)
		(fp_line
			(start 0.675 1.1)
			(end 0.675 0.65)
			(stroke
				(width 0.2)
				(type solid)
			)
			(layer "F.SilkS")
		)
		(fp_line
			(start 0.675 -0.65)
			(end 0.675 -1.1)
			(stroke
				(width 0.2)
				(type solid)
			)
			(layer "F.SilkS")
		)
		(fp_line
			(start 0.675 -1.1)
			(end -0.325 -1.1)
			(stroke
				(width 0.2)
				(type solid)
			)
			(layer "F.SilkS")
		)
		(fp_circle
			(center -1.125 -1.45)
			(end -1.25 -1.45)
			(stroke
				(width 0.25)
				(type solid)
			)
			(fill no)
			(layer "F.SilkS")
		)
		(pad "1" smd rect
			(at -1.125 -0.65)
			(size 0.5 0.9)
			(layers "F.Cu" "F.Mask" "F.Paste")
			(net "GND")
		)
		(pad "2" smd rect
			(at -1.125 0.65)
			(size 0.5 0.9)
			(layers "F.Cu" "F.Mask" "F.Paste")
			(net "+3.3V")
		)
		(pad "3" smd rect
			(at 1.125 0)
			(size 0.5 0.9)
			(layers "F.Cu" "F.Mask" "F.Paste")
			(net "FPGA_TDI")
		)
	)
)
